(kicad_pcb
	(version 20260206)
	(generator "pcbnew")
	(generator_version "10.0")
	(general
		(thickness 1.6)
		(legacy_teardrops no)
	)
	(paper "A4")
	(title_block
		(title "03242023_DA0F0TMBIJ0_F0T_Motherboard_J_brd_V01_OCP.brd")
		(comment 1 "Grand Teton / footprint 3039 of 6105 (U2), pads 2145-2254 of 4677")
	)
	(layers
		(0 "F.Cu" signal "TOP")
		(4 "In1.Cu" signal "GND")
		(6 "In2.Cu" signal "IN1")
		(8 "In3.Cu" signal "GND1")
		(10 "In4.Cu" signal "IN2")
		(12 "In5.Cu" signal "GND2")
		(14 "In6.Cu" signal "IN3")
		(16 "In7.Cu" signal "GND3")
		(18 "In8.Cu" signal "VCC")
		(20 "In9.Cu" signal "VCC1")
		(22 "In10.Cu" signal "GND4")
		(24 "In11.Cu" signal "IN4")
		(26 "In12.Cu" signal "GND5")
		(28 "In13.Cu" signal "IN5")
		(30 "In14.Cu" signal "GND6")
		(32 "In15.Cu" signal "IN6")
		(34 "In16.Cu" signal "GND7")
		(2 "B.Cu" signal "BOTTOM")
		(9 "F.Adhes" user "F.Adhesive")
		(11 "B.Adhes" user "B.Adhesive")
		(13 "F.Paste" user "Package Geometry/Pastemask Top")
		(15 "B.Paste" user "Package Geometry/Pastemask Bottom")
		(5 "F.SilkS" user "Ref Des/Silkscreen Top")
		(7 "B.SilkS" user "Ref Des/Silkscreen Bottom")
		(1 "F.Mask" user "Board Geometry/Soldermask Top")
		(3 "B.Mask" user "Board Geometry/Soldermask Bottom")
		(17 "Dwgs.User" user "User.Drawings")
		(19 "Cmts.User" user "User.Comments")
		(21 "Eco1.User" user "User.Eco1")
		(23 "Eco2.User" user "User.Eco2")
		(25 "Edge.Cuts" user "Board Geometry/Outline")
		(27 "Margin" user)
		(31 "F.CrtYd" user "Package Geometry/Place Bound Top")
		(29 "B.CrtYd" user "Package Geometry/Place Bound Bottom")
		(35 "F.Fab" user "Ref Des/Assembly Top")
		(33 "B.Fab" user "Ref Des/Assembly Bottom")
	)
	(footprint ""
		(layer "F.Cu")
		(at 359.870248 -251.76988 90)
		(property "Reference" "U2"
			(at -74.416158 -44.488608 0)
			(unlocked yes)
			(layer "F.SilkS")
			(effects
				(font
					(size 1.6002 1.1938)
					(thickness 0.1524)
				)
				(justify left)
			)
		)
		(property "Value" ""
			(at 0 0 90)
			(layer "F.Fab")
			(effects
				(font
					(size 1.27 1.27)
				)
			)
		)
		(duplicate_pad_numbers_are_jumpers no)
		(pad "CR5" smd circle
			(at -34.169604 7.698486 270)
			(size 0.4318 0.4318)
			(layers "F.Cu" "F.Mask" "F.Paste")
			(net "GND")
		)
		(pad "CR7" smd circle
			(at -32.541718 7.698486 270)
			(size 0.4318 0.4318)
			(layers "F.Cu" "F.Mask" "F.Paste")
			(net "UPI_CPU0_CPU1_P1P0_DN<15>")
		)
		(pad "CR9" smd circle
			(at -30.914086 7.698486 270)
			(size 0.4318 0.4318)
			(layers "F.Cu" "F.Mask" "F.Paste")
			(net "GND")
		)
		(pad "CR11" smd circle
			(at -29.2862 7.698486 270)
			(size 0.4318 0.4318)
			(layers "F.Cu" "F.Mask" "F.Paste")
			(net "GND")
		)
		(pad "CR13" smd circle
			(at -27.658314 7.698486 270)
			(size 0.4318 0.4318)
			(layers "F.Cu" "F.Mask" "F.Paste")
			(net "GND")
		)
		(pad "CR15" smd circle
			(at -26.030682 7.698486 270)
			(size 0.4318 0.4318)
			(layers "F.Cu" "F.Mask" "F.Paste")
			(net "P5E_CPU0_PE1_TX_DP<0>")
		)
		(pad "CR17" smd circle
			(at -24.402796 7.698486 270)
			(size 0.4318 0.4318)
			(layers "F.Cu" "F.Mask" "F.Paste")
			(net "GND")
		)
		(pad "CR19" smd circle
			(at -22.77491 7.698486 270)
			(size 0.4318 0.4318)
			(layers "F.Cu" "F.Mask" "F.Paste")
			(net "TP_H_SBLINK5_CPU0_PMSYNC")
		)
		(pad "CR21" smd circle
			(at -21.147278 7.698486 270)
			(size 0.4318 0.4318)
			(layers "F.Cu" "F.Mask" "F.Paste")
			(net "TP_IBL_SLPS3_CPU0_R_N")
		)
		(pad "CR23" smd circle
			(at -19.519392 7.698486 270)
			(size 0.4318 0.4318)
			(layers "F.Cu" "F.Mask" "F.Paste")
			(net "NC_CPU0_VIEWPIN_DIE10<0>")
		)
		(pad "CR25" smd circle
			(at -17.89176 7.698486 270)
			(size 0.4318 0.4318)
			(layers "F.Cu" "F.Mask" "F.Paste")
			(net "NC_CPU0_VIEWPIN_GNR2")
		)
		(pad "CR60" smd circle
			(at 12.19454 7.808468 270)
			(size 0.4318 0.4318)
			(layers "F.Cu" "F.Mask" "F.Paste")
			(net "NC_CPU0_LGSSPARE0")
		)
		(pad "CR62" smd circle
			(at 13.822426 7.808468 270)
			(size 0.4318 0.4318)
			(layers "F.Cu" "F.Mask" "F.Paste")
			(net "GND")
		)
		(pad "CR64" smd circle
			(at 15.450058 7.808468 270)
			(size 0.4318 0.4318)
			(layers "F.Cu" "F.Mask" "F.Paste")
			(net "GND")
		)
		(pad "CR66" smd circle
			(at 17.07769 7.808468 270)
			(size 0.4318 0.4318)
			(layers "F.Cu" "F.Mask" "F.Paste")
			(net "PVCCINFAON_CPU0")
		)
		(pad "CR68" smd circle
			(at 18.705576 7.808468 270)
			(size 0.4318 0.4318)
			(layers "F.Cu" "F.Mask" "F.Paste")
			(net "NC_CPU0_UPI3_APROBE<1>")
		)
		(pad "CR70" smd circle
			(at 20.333462 7.808468 270)
			(size 0.4318 0.4318)
			(layers "F.Cu" "F.Mask" "F.Paste")
			(net "PD_PIROM_CPU0_ADDR0")
		)
		(pad "CR72" smd circle
			(at 21.961094 7.808468 270)
			(size 0.4318 0.4318)
			(layers "F.Cu" "F.Mask" "F.Paste")
			(net "PU_PIROM_CPU0_SM_WP")
		)
		(pad "CR74" smd circle
			(at 23.58898 7.808468 270)
			(size 0.4318 0.4318)
			(layers "F.Cu" "F.Mask" "F.Paste")
			(net "Net_694")
		)
		(pad "CR76" smd circle
			(at 25.216612 7.808468 270)
			(size 0.4318 0.4318)
			(layers "F.Cu" "F.Mask" "F.Paste")
			(net "Net_671")
		)
		(pad "CR78" smd circle
			(at 26.844498 7.808468 270)
			(size 0.4318 0.4318)
			(layers "F.Cu" "F.Mask" "F.Paste")
			(net "GND")
		)
		(pad "CR80" smd circle
			(at 28.472384 7.808468 270)
			(size 0.4318 0.4318)
			(layers "F.Cu" "F.Mask" "F.Paste")
			(net "GND")
		)
		(pad "CR82" smd circle
			(at 30.100016 7.808468 270)
			(size 0.4318 0.4318)
			(layers "F.Cu" "F.Mask" "F.Paste")
			(net "GND")
		)
		(pad "CR84" smd circle
			(at 31.727902 7.808468 270)
			(size 0.4318 0.4318)
			(layers "F.Cu" "F.Mask" "F.Paste")
			(net "GND")
		)
		(pad "CR86" smd circle
			(at 33.355534 7.808468 270)
			(size 0.4318 0.4318)
			(layers "F.Cu" "F.Mask" "F.Paste")
			(net "P5E_CPU0_PE3_TX_DP<15>")
		)
		(pad "CR88" smd circle
			(at 34.98342 7.808468 270)
			(size 0.4318 0.4318)
			(layers "F.Cu" "F.Mask" "F.Paste")
			(net "GND")
		)
		(pad "CR90" smd circle
			(at 36.611306 7.808468 270)
			(size 0.4318 0.4318)
			(layers "F.Cu" "F.Mask" "F.Paste")
			(net "GND")
		)
		(pad "CT2" smd circle
			(at -36.611306 8.168132 270)
			(size 0.4318 0.4318)
			(layers "F.Cu" "F.Mask" "F.Paste")
			(net "UPI_CPU1_CPU0_P0P1_DP<16>")
		)
		(pad "CT4" smd circle
			(at -34.98342 8.168132 270)
			(size 0.4318 0.4318)
			(layers "F.Cu" "F.Mask" "F.Paste")
			(net "GND")
		)
		(pad "CT6" smd circle
			(at -33.355534 8.168132 270)
			(size 0.4318 0.4318)
			(layers "F.Cu" "F.Mask" "F.Paste")
			(net "UPI_CPU0_CPU1_P1P0_DP<15>")
		)
		(pad "CT8" smd circle
			(at -31.727902 8.168132 270)
			(size 0.4318 0.4318)
			(layers "F.Cu" "F.Mask" "F.Paste")
			(net "GND")
		)
		(pad "CT10" smd circle
			(at -30.100016 8.168132 270)
			(size 0.4318 0.4318)
			(layers "F.Cu" "F.Mask" "F.Paste")
			(net "GND")
		)
		(pad "CT12" smd circle
			(at -28.472384 8.168132 270)
			(size 0.4318 0.4318)
			(layers "F.Cu" "F.Mask" "F.Paste")
			(net "GND")
		)
		(pad "CT14" smd circle
			(at -26.844498 8.168132 270)
			(size 0.4318 0.4318)
			(layers "F.Cu" "F.Mask" "F.Paste")
			(net "P5E_CPU0_PE2_TX_DP<0>")
		)
		(pad "CT16" smd circle
			(at -25.216612 8.168132 270)
			(size 0.4318 0.4318)
			(layers "F.Cu" "F.Mask" "F.Paste")
			(net "GND")
		)
		(pad "CT18" smd circle
			(at -23.58898 8.168132 270)
			(size 0.4318 0.4318)
			(layers "F.Cu" "F.Mask" "F.Paste")
			(net "I3C_SPD_DDREFGH_CPU0_SDA")
		)
		(pad "CT20" smd circle
			(at -21.961094 8.168132 270)
			(size 0.4318 0.4318)
			(layers "F.Cu" "F.Mask" "F.Paste")
			(net "PD_CPU0_TXT_PLTEN")
		)
		(pad "CT22" smd circle
			(at -20.333462 8.168132 270)
			(size 0.4318 0.4318)
			(layers "F.Cu" "F.Mask" "F.Paste")
			(net "TP_JTAG_CPU0_PLD_TDI")
		)
		(pad "CT24" smd circle
			(at -18.705576 8.168132 270)
			(size 0.4318 0.4318)
			(layers "F.Cu" "F.Mask" "F.Paste")
			(net "TP_FM_IBL_ADR_TRIGGER_CPU0_R")
		)
		(pad "CT26" smd circle
			(at -17.07769 8.168132 270)
			(size 0.4318 0.4318)
			(layers "F.Cu" "F.Mask" "F.Paste")
			(net "NC_CPU0_VIEWPIN_GNR0")
		)
		(pad "CT61" smd circle
			(at 13.008356 8.278114 270)
			(size 0.4318 0.4318)
			(layers "F.Cu" "F.Mask" "F.Paste")
			(net "PU_CPU0_SOCKET_ID2")
		)
		(pad "CT63" smd circle
			(at 14.635988 8.278114 270)
			(size 0.4318 0.4318)
			(layers "F.Cu" "F.Mask" "F.Paste")
			(net "PVCCINFAON_CPU0")
		)
		(pad "CT65" smd circle
			(at 16.263874 8.278114 270)
			(size 0.4318 0.4318)
			(layers "F.Cu" "F.Mask" "F.Paste")
			(net "PVCCINFAON_CPU0")
		)
		(pad "CT67" smd circle
			(at 17.89176 8.278114 270)
			(size 0.4318 0.4318)
			(layers "F.Cu" "F.Mask" "F.Paste")
			(net "PVCCINFAON_CPU0")
		)
		(pad "CT69" smd circle
			(at 19.519392 8.278114 270)
			(size 0.4318 0.4318)
			(layers "F.Cu" "F.Mask" "F.Paste")
			(net "GND")
		)
		(pad "CT71" smd circle
			(at 21.147278 8.278114 270)
			(size 0.4318 0.4318)
			(layers "F.Cu" "F.Mask" "F.Paste")
			(net "PD_PIROM_CPU0_ADDR1")
		)
		(pad "CT73" smd circle
			(at 22.77491 8.278114 270)
			(size 0.4318 0.4318)
			(layers "F.Cu" "F.Mask" "F.Paste")
			(net "GND")
		)
		(pad "CT75" smd circle
			(at 24.402796 8.278114 270)
			(size 0.4318 0.4318)
			(layers "F.Cu" "F.Mask" "F.Paste")
			(net "Net_695")
		)
		(pad "CT77" smd circle
			(at 26.030682 8.278114 270)
			(size 0.4318 0.4318)
			(layers "F.Cu" "F.Mask" "F.Paste")
			(net "PVCCFA_EHV_FIVRA_CPU0")
		)
		(pad "CT79" smd circle
			(at 27.658314 8.278114 270)
			(size 0.4318 0.4318)
			(layers "F.Cu" "F.Mask" "F.Paste")
			(net "GND")
		)
		(pad "CT81" smd circle
			(at 29.2862 8.278114 270)
			(size 0.4318 0.4318)
			(layers "F.Cu" "F.Mask" "F.Paste")
			(net "GND")
		)
		(pad "CT83" smd circle
			(at 30.914086 8.278114 270)
			(size 0.4318 0.4318)
			(layers "F.Cu" "F.Mask" "F.Paste")
			(net "GND")
		)
		(pad "CT85" smd circle
			(at 32.541718 8.278114 270)
			(size 0.4318 0.4318)
			(layers "F.Cu" "F.Mask" "F.Paste")
			(net "PVCCFA_EHV_FIVRA_CPU0")
		)
		(pad "CT87" smd circle
			(at 34.169604 8.278114 270)
			(size 0.4318 0.4318)
			(layers "F.Cu" "F.Mask" "F.Paste")
			(net "P5E_CPU0_PE3_TX_DN<14>")
		)
		(pad "CT89" smd circle
			(at 35.797236 8.278114 270)
			(size 0.4318 0.4318)
			(layers "F.Cu" "F.Mask" "F.Paste")
			(net "GND")
		)
		(pad "CT91" smd oval
			(at 37.425122 8.278114)
			(size 0.381 0.4826)
			(drill
				(offset 0 -0.0508)
			)
			(layers "F.Cu" "F.Mask" "F.Paste")
			(net "P5E_CPU0_PE3_RX_DP<15>")
		)
		(pad "CU1" smd oval
			(at -37.425122 8.638286 180)
			(size 0.381 0.4826)
			(drill
				(offset 0 -0.0508)
			)
			(layers "F.Cu" "F.Mask" "F.Paste")
			(net "UPI_CPU1_CPU0_P0P1_DP<15>")
		)
		(pad "CU3" smd circle
			(at -35.797236 8.638286 270)
			(size 0.4318 0.4318)
			(layers "F.Cu" "F.Mask" "F.Paste")
			(net "PVCCINFAON_CPU0")
		)
		(pad "CU5" smd circle
			(at -34.169604 8.638286 270)
			(size 0.4318 0.4318)
			(layers "F.Cu" "F.Mask" "F.Paste")
			(net "UPI_CPU0_CPU1_P1P0_DP<14>")
		)
		(pad "CU7" smd circle
			(at -32.541718 8.638286 270)
			(size 0.4318 0.4318)
			(layers "F.Cu" "F.Mask" "F.Paste")
			(net "PVCCINFAON_CPU0")
		)
		(pad "CU9" smd circle
			(at -30.914086 8.638286 270)
			(size 0.4318 0.4318)
			(layers "F.Cu" "F.Mask" "F.Paste")
			(net "P5E_CPU0_PE2_RX_DN<0>")
		)
		(pad "CU11" smd circle
			(at -29.2862 8.638286 270)
			(size 0.4318 0.4318)
			(layers "F.Cu" "F.Mask" "F.Paste")
			(net "PVCCINFAON_CPU0")
		)
		(pad "CU13" smd circle
			(at -27.658314 8.638286 270)
			(size 0.4318 0.4318)
			(layers "F.Cu" "F.Mask" "F.Paste")
			(net "P5E_CPU0_PE2_TX_DN<0>")
		)
		(pad "CU15" smd circle
			(at -26.030682 8.638286 270)
			(size 0.4318 0.4318)
			(layers "F.Cu" "F.Mask" "F.Paste")
			(net "PVCCINFAON_CPU0")
		)
		(pad "CU17" smd circle
			(at -24.402796 8.638286 270)
			(size 0.4318 0.4318)
			(layers "F.Cu" "F.Mask" "F.Paste")
			(net "I3C_SPD_DDREFGH_CPU0_SCL")
		)
		(pad "CU19" smd circle
			(at -22.77491 8.638286 270)
			(size 0.4318 0.4318)
			(layers "F.Cu" "F.Mask" "F.Paste")
			(net "GND")
		)
		(pad "CU21" smd circle
			(at -21.147278 8.638286 270)
			(size 0.4318 0.4318)
			(layers "F.Cu" "F.Mask" "F.Paste")
			(net "GND")
		)
		(pad "CU23" smd circle
			(at -19.519392 8.638286 270)
			(size 0.4318 0.4318)
			(layers "F.Cu" "F.Mask" "F.Paste")
			(net "GND")
		)
		(pad "CU25" smd circle
			(at -17.89176 8.638286 270)
			(size 0.4318 0.4318)
			(layers "F.Cu" "F.Mask" "F.Paste")
			(net "GND")
		)
		(pad "CU60" smd circle
			(at 12.19454 8.748268 270)
			(size 0.4318 0.4318)
			(layers "F.Cu" "F.Mask" "F.Paste")
			(net "GND")
		)
		(pad "CU62" smd circle
			(at 13.822426 8.748268 270)
			(size 0.4318 0.4318)
			(layers "F.Cu" "F.Mask" "F.Paste")
			(net "NC_CPU0_LGSSPARE2")
		)
		(pad "CU64" smd circle
			(at 15.450058 8.748268 270)
			(size 0.4318 0.4318)
			(layers "F.Cu" "F.Mask" "F.Paste")
			(net "PVCCINFAON_CPU0")
		)
		(pad "CU66" smd circle
			(at 17.07769 8.748268 270)
			(size 0.4318 0.4318)
			(layers "F.Cu" "F.Mask" "F.Paste")
			(net "GND")
		)
		(pad "CU68" smd circle
			(at 18.705576 8.748268 270)
			(size 0.4318 0.4318)
			(layers "F.Cu" "F.Mask" "F.Paste")
			(net "GND")
		)
		(pad "CU70" smd circle
			(at 20.333462 8.748268 270)
			(size 0.4318 0.4318)
			(layers "F.Cu" "F.Mask" "F.Paste")
			(net "SMB_S3M_CPU0_PIROM_3V3AUX_SCL_1")
		)
		(pad "CU72" smd circle
			(at 21.961094 8.748268 270)
			(size 0.4318 0.4318)
			(layers "F.Cu" "F.Mask" "F.Paste")
			(net "GND")
		)
		(pad "CU74" smd circle
			(at 23.58898 8.748268 270)
			(size 0.4318 0.4318)
			(layers "F.Cu" "F.Mask" "F.Paste")
			(net "Net_670")
		)
		(pad "CU76" smd circle
			(at 25.216612 8.748268 270)
			(size 0.4318 0.4318)
			(layers "F.Cu" "F.Mask" "F.Paste")
			(net "Net_696")
		)
		(pad "CU78" smd circle
			(at 26.844498 8.748268 270)
			(size 0.4318 0.4318)
			(layers "F.Cu" "F.Mask" "F.Paste")
			(net "GND")
		)
		(pad "CU80" smd circle
			(at 28.472384 8.748268 270)
			(size 0.4318 0.4318)
			(layers "F.Cu" "F.Mask" "F.Paste")
			(net "GND")
		)
		(pad "CU82" smd circle
			(at 30.100016 8.748268 270)
			(size 0.4318 0.4318)
			(layers "F.Cu" "F.Mask" "F.Paste")
			(net "GND")
		)
		(pad "CU84" smd circle
			(at 31.727902 8.748268 270)
			(size 0.4318 0.4318)
			(layers "F.Cu" "F.Mask" "F.Paste")
			(net "GND")
		)
		(pad "CU86" smd circle
			(at 33.355534 8.748268 270)
			(size 0.4318 0.4318)
			(layers "F.Cu" "F.Mask" "F.Paste")
			(net "P5E_CPU0_PE3_TX_DP<14>")
		)
		(pad "CU88" smd circle
			(at 34.98342 8.748268 270)
			(size 0.4318 0.4318)
			(layers "F.Cu" "F.Mask" "F.Paste")
			(net "GND")
		)
		(pad "CU90" smd circle
			(at 36.611306 8.748268 270)
			(size 0.4318 0.4318)
			(layers "F.Cu" "F.Mask" "F.Paste")
			(net "P5E_CPU0_PE3_RX_DN<15>")
		)
		(pad "CV2" smd circle
			(at -36.611306 9.107932 270)
			(size 0.4318 0.4318)
			(layers "F.Cu" "F.Mask" "F.Paste")
			(net "UPI_CPU1_CPU0_P0P1_DN<15>")
		)
		(pad "CV4" smd circle
			(at -34.98342 9.107932 270)
			(size 0.4318 0.4318)
			(layers "F.Cu" "F.Mask" "F.Paste")
			(net "GND")
		)
		(pad "CV6" smd circle
			(at -33.355534 9.107932 270)
			(size 0.4318 0.4318)
			(layers "F.Cu" "F.Mask" "F.Paste")
			(net "UPI_CPU0_CPU1_P1P0_DN<14>")
		)
		(pad "CV8" smd circle
			(at -31.727902 9.107932 270)
			(size 0.4318 0.4318)
			(layers "F.Cu" "F.Mask" "F.Paste")
			(net "GND")
		)
		(pad "CV10" smd circle
			(at -30.100016 9.107932 270)
			(size 0.4318 0.4318)
			(layers "F.Cu" "F.Mask" "F.Paste")
			(net "P5E_CPU0_PE2_RX_DP<0>")
		)
		(pad "CV12" smd circle
			(at -28.472384 9.107932 270)
			(size 0.4318 0.4318)
			(layers "F.Cu" "F.Mask" "F.Paste")
			(net "GND")
		)
		(pad "CV14" smd circle
			(at -26.844498 9.107932 270)
			(size 0.4318 0.4318)
			(layers "F.Cu" "F.Mask" "F.Paste")
			(net "P5E_CPU0_PE2_TX_DN<1>")
		)
		(pad "CV16" smd circle
			(at -25.216612 9.107932 270)
			(size 0.4318 0.4318)
			(layers "F.Cu" "F.Mask" "F.Paste")
			(net "GND")
		)
		(pad "CV18" smd circle
			(at -23.58898 9.107932 270)
			(size 0.4318 0.4318)
			(layers "F.Cu" "F.Mask" "F.Paste")
			(net "TP_H_SBLINK5_CPU0_PMDOWN")
		)
		(pad "CV20" smd circle
			(at -21.961094 9.107932 270)
			(size 0.4318 0.4318)
			(layers "F.Cu" "F.Mask" "F.Paste")
			(net "PWRGD_PLT_AUX_CPU0_LVT3")
		)
		(pad "CV22" smd circle
			(at -20.333462 9.107932 270)
			(size 0.4318 0.4318)
			(layers "F.Cu" "F.Mask" "F.Paste")
			(net "TP_JTAG_CPU0_PLD_TMS")
		)
		(pad "CV24" smd circle
			(at -18.705576 9.107932 270)
			(size 0.4318 0.4318)
			(layers "F.Cu" "F.Mask" "F.Paste")
			(net "NC_CPU0_VIEWPIN_DIE10<2>")
		)
		(pad "CV26" smd circle
			(at -17.07769 9.107932 270)
			(size 0.4318 0.4318)
			(layers "F.Cu" "F.Mask" "F.Paste")
			(net "GND")
		)
		(pad "CV61" smd circle
			(at 13.008356 9.217914 270)
			(size 0.4318 0.4318)
			(layers "F.Cu" "F.Mask" "F.Paste")
			(net "PVCCINFAON_CPU0")
		)
		(pad "CV63" smd circle
			(at 14.635988 9.217914 270)
			(size 0.4318 0.4318)
			(layers "F.Cu" "F.Mask" "F.Paste")
			(net "PVCCINFAON_CPU0")
		)
		(pad "CV65" smd circle
			(at 16.263874 9.217914 270)
			(size 0.4318 0.4318)
			(layers "F.Cu" "F.Mask" "F.Paste")
			(net "PVCCINFAON_CPU0")
		)
		(pad "CV67" smd circle
			(at 17.89176 9.217914 270)
			(size 0.4318 0.4318)
			(layers "F.Cu" "F.Mask" "F.Paste")
			(net "PVCCINFAON_CPU0")
		)
		(pad "CV69" smd circle
			(at 19.519392 9.217914 270)
			(size 0.4318 0.4318)
			(layers "F.Cu" "F.Mask" "F.Paste")
			(net "NC_UART_IBL_CPU0_TXD")
		)
		(pad "CV71" smd circle
			(at 21.147278 9.217914 270)
			(size 0.4318 0.4318)
			(layers "F.Cu" "F.Mask" "F.Paste")
			(net "NC_UART_IBL_CPU0_CTS")
		)
		(pad "CV73" smd circle
			(at 22.77491 9.217914 270)
			(size 0.4318 0.4318)
			(layers "F.Cu" "F.Mask" "F.Paste")
			(net "Net_686")
		)
		(pad "CV75" smd circle
			(at 24.402796 9.217914 270)
			(size 0.4318 0.4318)
			(layers "F.Cu" "F.Mask" "F.Paste")
			(net "GND")
		)
		(pad "CV77" smd circle
			(at 26.030682 9.217914 270)
			(size 0.4318 0.4318)
			(layers "F.Cu" "F.Mask" "F.Paste")
			(net "Net_672")
		)
		(pad "CV79" smd circle
			(at 27.658314 9.217914 270)
			(size 0.4318 0.4318)
			(layers "F.Cu" "F.Mask" "F.Paste")
			(net "GND")
		)
		(pad "CV81" smd circle
			(at 29.2862 9.217914 270)
			(size 0.4318 0.4318)
			(layers "F.Cu" "F.Mask" "F.Paste")
			(net "GND")
		)
		(pad "CV83" smd circle
			(at 30.914086 9.217914 270)
			(size 0.4318 0.4318)
			(layers "F.Cu" "F.Mask" "F.Paste")
			(net "GND")
		)
	)
)
